(kicad_pcb
	(version 20260206)
	(generator "pcbnew")
	(generator_version "10.0")
	(general
		(thickness 1.6)
		(legacy_teardrops no)
	)
	(paper "A4")
	(title_block
		(title "01162023_DA0F0TEBIF0_F0T_Expander_BD_F_brd_V02_OCP.brd")
		(comment 1 "Grand Teton / footprints 6800-6805 of 9728")
	)
	(layers
		(0 "F.Cu" signal "TOP")
		(4 "In1.Cu" signal "GND")
		(6 "In2.Cu" signal "VCC")
		(8 "In3.Cu" signal "VCC1")
		(10 "In4.Cu" signal "GND1")
		(12 "In5.Cu" signal "IN1")
		(14 "In6.Cu" signal "GND2")
		(16 "In7.Cu" signal "IN2")
		(18 "In8.Cu" signal "GND3")
		(20 "In9.Cu" signal "IN3")
		(22 "In10.Cu" signal "GND4")
		(24 "In11.Cu" signal "IN4")
		(26 "In12.Cu" signal "GND5")
		(28 "In13.Cu" signal "IN5")
		(30 "In14.Cu" signal "GND6")
		(32 "In15.Cu" signal "IN6")
		(34 "In16.Cu" signal "GND7")
		(2 "B.Cu" signal "BOTTOM")
		(9 "F.Adhes" user "F.Adhesive")
		(11 "B.Adhes" user "B.Adhesive")
		(13 "F.Paste" user "Package Geometry/Pastemask Top")
		(15 "B.Paste" user "Package Geometry/Pastemask Bottom")
		(5 "F.SilkS" user "Ref Des/Silkscreen Top")
		(7 "B.SilkS" user "Ref Des/Silkscreen Bottom")
		(1 "F.Mask" user "Board Geometry/Soldermask Top")
		(3 "B.Mask" user "Board Geometry/Soldermask Bottom")
		(17 "Dwgs.User" user "User.Drawings")
		(19 "Cmts.User" user "User.Comments")
		(21 "Eco1.User" user "User.Eco1")
		(23 "Eco2.User" user "User.Eco2")
		(25 "Edge.Cuts" user "Board Geometry/Outline")
		(27 "Margin" user)
		(31 "F.CrtYd" user "Package Geometry/Place Bound Top")
		(29 "B.CrtYd" user "Package Geometry/Place Bound Bottom")
		(35 "F.Fab" user "Ref Des/Assembly Top")
		(33 "B.Fab" user "Ref Des/Assembly Bottom")
	)
	(footprint ""
		(layer "F.Cu")
		(at 222.552006 -195.22821 -90)
		(property "Reference" "U305"
			(at 0 0 270)
			(layer "F.SilkS")
			(hide yes)
			(effects
				(font
					(size 1.27 1.27)
				)
			)
		)
		(property "Value" ""
			(at 0 0 270)
			(layer "F.Fab")
			(effects
				(font
					(size 1.27 1.27)
				)
			)
		)
		(duplicate_pad_numbers_are_jumpers no)
		(fp_line
			(start -1.0414 1.575054)
			(end -1.0414 -1.575054)
			(stroke
				(width 0.1524)
				(type default)
			)
			(layer "F.SilkS")
		)
		(fp_line
			(start 1.0414 1.575054)
			(end -1.0414 1.575054)
			(stroke
				(width 0.1524)
				(type default)
			)
			(layer "F.SilkS")
		)
		(fp_line
			(start 0 -1.272032)
			(end -0.254 -1.575054)
			(stroke
				(width 0.1524)
				(type default)
			)
			(layer "F.SilkS")
		)
		(fp_line
			(start -1.0414 -1.575054)
			(end -0.254 -1.575054)
			(stroke
				(width 0.1524)
				(type default)
			)
			(layer "F.SilkS")
		)
		(fp_line
			(start 0.2286 -1.575054)
			(end 0 -1.272032)
			(stroke
				(width 0.1524)
				(type default)
			)
			(layer "F.SilkS")
		)
		(fp_line
			(start 0.254 -1.575054)
			(end 1.0414 -1.575054)
			(stroke
				(width 0.1524)
				(type default)
			)
			(layer "F.SilkS")
		)
		(fp_line
			(start 1.0414 -1.575054)
			(end 1.0414 1.575054)
			(stroke
				(width 0.1524)
				(type default)
			)
			(layer "F.SilkS")
		)
		(fp_poly
			(pts
				(xy -2.710688 -0.975106) (xy -3.726688 -1.483106) (xy -3.726688 -0.467106)
			)
			(stroke
				(width 0)
				(type default)
			)
			(fill yes)
			(layer "F.SilkS")
		)
		(fp_line
			(start -1.4478 1.5748)
			(end -1.4478 1.2192)
			(stroke
				(width 0.1)
				(type default)
			)
			(layer "F.Fab")
		)
		(fp_line
			(start 1.4478 1.5748)
			(end -1.4478 1.5748)
			(stroke
				(width 0.1)
				(type default)
			)
			(layer "F.Fab")
		)
		(fp_line
			(start -2.5654 1.2192)
			(end -2.5654 -1.2192)
			(stroke
				(width 0.1)
				(type default)
			)
			(layer "F.Fab")
		)
		(fp_line
			(start -1.4478 1.2192)
			(end -2.5654 1.2192)
			(stroke
				(width 0.1)
				(type default)
			)
			(layer "F.Fab")
		)
		(fp_line
			(start 1.4478 1.2192)
			(end 1.4478 1.5748)
			(stroke
				(width 0.1)
				(type default)
			)
			(layer "F.Fab")
		)
		(fp_line
			(start 2.5654 1.2192)
			(end 1.4478 1.2192)
			(stroke
				(width 0.1)
				(type default)
			)
			(layer "F.Fab")
		)
		(fp_line
			(start -2.5654 -1.2192)
			(end -1.4478 -1.2192)
			(stroke
				(width 0.1)
				(type default)
			)
			(layer "F.Fab")
		)
		(fp_line
			(start -1.4478 -1.2192)
			(end -1.4478 -1.5748)
			(stroke
				(width 0.1)
				(type default)
			)
			(layer "F.Fab")
		)
		(fp_line
			(start 1.4478 -1.2192)
			(end 2.5654 -1.2192)
			(stroke
				(width 0.1)
				(type default)
			)
			(layer "F.Fab")
		)
		(fp_line
			(start 2.5654 -1.2192)
			(end 2.5654 1.2192)
			(stroke
				(width 0.1)
				(type default)
			)
			(layer "F.Fab")
		)
		(fp_line
			(start -1.4478 -1.5748)
			(end 1.4478 -1.5748)
			(stroke
				(width 0.1)
				(type default)
			)
			(layer "F.Fab")
		)
		(fp_line
			(start 1.4478 -1.5748)
			(end 1.4478 -1.2192)
			(stroke
				(width 0.1)
				(type default)
			)
			(layer "F.Fab")
		)
		(fp_poly
			(pts
				(xy -2.710688 -0.975106) (xy -3.726688 -1.483106) (xy -3.726688 -0.467106)
			)
			(stroke
				(width 0)
				(type default)
			)
			(fill yes)
			(layer "F.Fab")
		)
		(pad "1" smd rect
			(at -1.849882 -0.975106 180)
			(size 0.3556 1.3208)
			(layers "F.Cu" "F.Mask" "F.Paste")
			(net "SPI_BIC1_CLK_R5")
		)
		(pad "2" smd rect
			(at -1.849882 -0.32512 180)
			(size 0.3556 1.3208)
			(layers "F.Cu" "F.Mask" "F.Paste")
			(net "SPI_BIC1_MISO_R5")
		)
		(pad "3" smd rect
			(at -1.849882 0.32512 180)
			(size 0.3556 1.3208)
			(layers "F.Cu" "F.Mask" "F.Paste")
			(net "SPI_BIC1_MOSI_R5")
		)
		(pad "4" smd rect
			(at -1.849882 0.975106 180)
			(size 0.3556 1.3208)
			(layers "F.Cu" "F.Mask" "F.Paste")
			(net "GND")
		)
		(pad "5" smd rect
			(at 1.849882 0.975106 180)
			(size 0.3556 1.3208)
			(layers "F.Cu" "F.Mask" "F.Paste")
			(net "SPI2_DO_BUF")
		)
		(pad "6" smd rect
			(at 1.849882 0.32512 180)
			(size 0.3556 1.3208)
			(layers "F.Cu" "F.Mask" "F.Paste")
			(net "SPI2_DI_BUF")
		)
		(pad "7" smd rect
			(at 1.849882 -0.32512 180)
			(size 0.3556 1.3208)
			(layers "F.Cu" "F.Mask" "F.Paste")
			(net "SPI2_CLK_BUF")
		)
		(pad "8" smd rect
			(at 1.849882 -0.975106 180)
			(size 0.3556 1.3208)
			(layers "F.Cu" "F.Mask" "F.Paste")
			(net "P3V3_AUX")
		)
	)
	(footprint ""
		(layer "F.Cu")
		(at 104.724454 -119.77624)
		(property "Reference" "Q213"
			(at 0.63754 -1.933194 0)
			(unlocked yes)
			(layer "F.SilkS")
			(effects
				(font
					(size 0.7874 0.5842)
					(thickness 0.1524)
				)
			)
		)
		(property "Value" ""
			(at 0 0 0)
			(layer "F.Fab")
			(effects
				(font
					(size 1.27 1.27)
				)
			)
		)
		(duplicate_pad_numbers_are_jumpers no)
		(fp_line
			(start -1.376172 -1.199896)
			(end -0.508 -1.199896)
			(stroke
				(width 0.1524)
				(type default)
			)
			(layer "F.SilkS")
		)
		(fp_line
			(start -1.376172 1.199896)
			(end -1.376172 -1.199896)
			(stroke
				(width 0.1524)
				(type default)
			)
			(layer "F.SilkS")
		)
		(fp_line
			(start -0.508 -1.199896)
			(end 0 -0.762)
			(stroke
				(width 0.1524)
				(type default)
			)
			(layer "F.SilkS")
		)
		(fp_line
			(start 0 -0.762)
			(end 0.508 -1.199896)
			(stroke
				(width 0.1524)
				(type default)
			)
			(layer "F.SilkS")
		)
		(fp_line
			(start 0.508 -1.199896)
			(end 1.376172 -1.199896)
			(stroke
				(width 0.1524)
				(type default)
			)
			(layer "F.SilkS")
		)
		(fp_line
			(start 1.376172 -1.199896)
			(end 1.376172 1.199896)
			(stroke
				(width 0.1524)
				(type default)
			)
			(layer "F.SilkS")
		)
		(fp_line
			(start 1.376172 1.199896)
			(end -1.376172 1.199896)
			(stroke
				(width 0.1524)
				(type default)
			)
			(layer "F.SilkS")
		)
		(fp_poly
			(pts
				(xy -1.048766 -1.358138) (xy -1.31826 -2.166366) (xy -1.856994 -1.627632)
			)
			(stroke
				(width 0)
				(type default)
			)
			(fill yes)
			(layer "F.SilkS")
		)
		(fp_line
			(start -0.674878 -1.100074)
			(end 0.674878 -1.100074)
			(stroke
				(width 0.1)
				(type default)
			)
			(layer "F.Fab")
		)
		(fp_line
			(start -0.674878 1.100074)
			(end -0.674878 -1.100074)
			(stroke
				(width 0.1)
				(type default)
			)
			(layer "F.Fab")
		)
		(fp_line
			(start 0.674878 -1.100074)
			(end 0.674878 1.100074)
			(stroke
				(width 0.1)
				(type default)
			)
			(layer "F.Fab")
		)
		(fp_line
			(start 0.674878 1.100074)
			(end -0.674878 1.100074)
			(stroke
				(width 0.1)
				(type default)
			)
			(layer "F.Fab")
		)
		(fp_poly
			(pts
				(xy -1.4605 -0.7493) (xy -2.2225 -1.1303) (xy -2.2225 -0.3683)
			)
			(stroke
				(width 0)
				(type default)
			)
			(fill yes)
			(layer "F.Fab")
		)
		(pad "1" smd rect
			(at -0.899922 -0.750062 270)
			(size 0.6096 0.6096)
			(layers "F.Cu" "F.Mask" "F.Paste")
			(net "GND")
		)
		(pad "2" smd rect
			(at -0.899922 0 270)
			(size 0.4064 0.6096)
			(layers "F.Cu" "F.Mask" "F.Paste")
			(net "P3V3_NIC1_PG_G1")
		)
		(pad "3" smd rect
			(at -0.899922 0.750062 270)
			(size 0.6096 0.6096)
			(layers "F.Cu" "F.Mask" "F.Paste")
			(net "PWRGD_P3V3_NIC1_D")
		)
		(pad "4" smd rect
			(at 0.899922 0.750062 270)
			(size 0.6096 0.6096)
			(layers "F.Cu" "F.Mask" "F.Paste")
			(net "GND")
		)
		(pad "5" smd rect
			(at 0.899922 0 270)
			(size 0.4064 0.6096)
			(layers "F.Cu" "F.Mask" "F.Paste")
			(net "P3V3_NIC1_PG_G2")
		)
		(pad "6" smd rect
			(at 0.899922 -0.750062 270)
			(size 0.6096 0.6096)
			(layers "F.Cu" "F.Mask" "F.Paste")
			(net "P3V3_NIC1_PG_G2")
		)
	)
	(footprint ""
		(layer "F.Cu")
		(at 314.861448 -145.311114 180)
		(property "Reference" "C435"
			(at 0 0 180)
			(layer "F.SilkS")
			(hide yes)
			(effects
				(font
					(size 1.27 1.27)
				)
			)
		)
		(property "Value" ""
			(at 0 0 180)
			(layer "F.Fab")
			(effects
				(font
					(size 1.27 1.27)
				)
			)
		)
		(duplicate_pad_numbers_are_jumpers no)
		(fp_line
			(start 0.299974 0.150114)
			(end -0.299974 0.150114)
			(stroke
				(width 0.1)
				(type default)
			)
			(layer "F.Fab")
		)
		(fp_line
			(start 0.299974 -0.150114)
			(end 0.299974 0.150114)
			(stroke
				(width 0.1)
				(type default)
			)
			(layer "F.Fab")
		)
		(fp_line
			(start -0.299974 0.150114)
			(end -0.299974 -0.150114)
			(stroke
				(width 0.1)
				(type default)
			)
			(layer "F.Fab")
		)
		(fp_line
			(start -0.299974 -0.150114)
			(end 0.299974 -0.150114)
			(stroke
				(width 0.1)
				(type default)
			)
			(layer "F.Fab")
		)
		(pad "1" smd rect
			(at -0.2667 0 180)
			(size 0.3048 0.381)
			(layers "F.Cu" "F.Mask" "F.Paste")
			(net "P5E_PEX2_STN0_TX_DP<9>")
		)
		(pad "2" smd rect
			(at 0.2667 0 180)
			(size 0.3048 0.381)
			(layers "F.Cu" "F.Mask" "F.Paste")
			(net "P5E_PEX2_STN0_TX_C_DP<9>")
		)
	)
	(footprint ""
		(layer "F.Cu")
		(at 219.202 -197.612)
		(property "Reference" "R1523"
			(at 0 0 0)
			(layer "F.SilkS")
			(hide yes)
			(effects
				(font
					(size 1.27 1.27)
				)
			)
		)
		(property "Value" ""
			(at 0 0 0)
			(layer "F.Fab")
			(effects
				(font
					(size 1.27 1.27)
				)
			)
		)
		(duplicate_pad_numbers_are_jumpers no)
		(fp_line
			(start -0.7874 -0.4064)
			(end 0.7874 -0.4064)
			(stroke
				(width 0.1524)
				(type default)
			)
			(layer "F.SilkS")
		)
		(fp_line
			(start -0.7874 0.4064)
			(end -0.7874 -0.4064)
			(stroke
				(width 0.1524)
				(type default)
			)
			(layer "F.SilkS")
		)
		(fp_line
			(start 0.7874 -0.4064)
			(end 0.7874 0.4064)
			(stroke
				(width 0.1524)
				(type default)
			)
			(layer "F.SilkS")
		)
		(fp_line
			(start 0.7874 0.4064)
			(end -0.7874 0.4064)
			(stroke
				(width 0.1524)
				(type default)
			)
			(layer "F.SilkS")
		)
		(fp_line
			(start -0.67945 -0.305054)
			(end -0.12065 -0.305054)
			(stroke
				(width 0.1)
				(type default)
			)
			(layer "F.Fab")
		)
		(fp_line
			(start -0.67945 0.3048)
			(end -0.67945 -0.305054)
			(stroke
				(width 0.1)
				(type default)
			)
			(layer "F.Fab")
		)
		(fp_line
			(start -0.12065 -0.305054)
			(end -0.12065 -0.2794)
			(stroke
				(width 0.1)
				(type default)
			)
			(layer "F.Fab")
		)
		(fp_line
			(start -0.12065 -0.2794)
			(end 0.12065 -0.2794)
			(stroke
				(width 0.1)
				(type default)
			)
			(layer "F.Fab")
		)
		(fp_line
			(start -0.12065 0.2794)
			(end -0.12065 0.3048)
			(stroke
				(width 0.1)
				(type default)
			)
			(layer "F.Fab")
		)
		(fp_line
			(start -0.12065 0.3048)
			(end -0.67945 0.3048)
			(stroke
				(width 0.1)
				(type default)
			)
			(layer "F.Fab")
		)
		(fp_line
			(start 0.120396 0.2794)
			(end -0.12065 0.2794)
			(stroke
				(width 0.1)
				(type default)
			)
			(layer "F.Fab")
		)
		(fp_line
			(start 0.120396 0.3048)
			(end 0.120396 0.2794)
			(stroke
				(width 0.1)
				(type default)
			)
			(layer "F.Fab")
		)
		(fp_line
			(start 0.12065 -0.3048)
			(end 0.67945 -0.3048)
			(stroke
				(width 0.1)
				(type default)
			)
			(layer "F.Fab")
		)
		(fp_line
			(start 0.12065 -0.2794)
			(end 0.12065 -0.3048)
			(stroke
				(width 0.1)
				(type default)
			)
			(layer "F.Fab")
		)
		(fp_line
			(start 0.67945 -0.3048)
			(end 0.67945 0.3048)
			(stroke
				(width 0.1)
				(type default)
			)
			(layer "F.Fab")
		)
		(fp_line
			(start 0.67945 0.3048)
			(end 0.120396 0.3048)
			(stroke
				(width 0.1)
				(type default)
			)
			(layer "F.Fab")
		)
		(pad "1" smd circle
			(at -0.40005 0)
			(size 0 0)
			(layers "F.Cu" "F.Mask" "F.Paste")
			(net "SMB_NIC6_LS_R_SCL")
		)
		(pad "2" smd circle
			(at 0.40005 0)
			(size 0 0)
			(layers "F.Cu" "F.Mask" "F.Paste")
			(net "P3V3_NIC6")
		)
	)
	(footprint ""
		(layer "F.Cu")
		(at 245.825264 -119.105426 90)
		(property "Reference" "R6040"
			(at 0 0 90)
			(layer "F.SilkS")
			(hide yes)
			(effects
				(font
					(size 1.27 1.27)
				)
			)
		)
		(property "Value" ""
			(at 0 0 90)
			(layer "F.Fab")
			(effects
				(font
					(size 1.27 1.27)
				)
			)
		)
		(duplicate_pad_numbers_are_jumpers no)
		(fp_line
			(start 0.7874 -0.4064)
			(end 0.7874 0.4064)
			(stroke
				(width 0.1524)
				(type default)
			)
			(layer "F.SilkS")
		)
		(fp_line
			(start -0.7874 -0.4064)
			(end 0.7874 -0.4064)
			(stroke
				(width 0.1524)
				(type default)
			)
			(layer "F.SilkS")
		)
		(fp_line
			(start 0.7874 0.4064)
			(end -0.7874 0.4064)
			(stroke
				(width 0.1524)
				(type default)
			)
			(layer "F.SilkS")
		)
		(fp_line
			(start -0.7874 0.4064)
			(end -0.7874 -0.4064)
			(stroke
				(width 0.1524)
				(type default)
			)
			(layer "F.SilkS")
		)
		(fp_line
			(start -0.12065 -0.305054)
			(end -0.12065 -0.2794)
			(stroke
				(width 0.1)
				(type default)
			)
			(layer "F.Fab")
		)
		(fp_line
			(start -0.67945 -0.305054)
			(end -0.12065 -0.305054)
			(stroke
				(width 0.1)
				(type default)
			)
			(layer "F.Fab")
		)
		(fp_line
			(start 0.67945 -0.3048)
			(end 0.67945 0.3048)
			(stroke
				(width 0.1)
				(type default)
			)
			(layer "F.Fab")
		)
		(fp_line
			(start 0.12065 -0.3048)
			(end 0.67945 -0.3048)
			(stroke
				(width 0.1)
				(type default)
			)
			(layer "F.Fab")
		)
		(fp_line
			(start 0.12065 -0.2794)
			(end 0.12065 -0.3048)
			(stroke
				(width 0.1)
				(type default)
			)
			(layer "F.Fab")
		)
		(fp_line
			(start -0.12065 -0.2794)
			(end 0.12065 -0.2794)
			(stroke
				(width 0.1)
				(type default)
			)
			(layer "F.Fab")
		)
		(fp_line
			(start 0.120396 0.2794)
			(end -0.12065 0.2794)
			(stroke
				(width 0.1)
				(type default)
			)
			(layer "F.Fab")
		)
		(fp_line
			(start -0.12065 0.2794)
			(end -0.12065 0.3048)
			(stroke
				(width 0.1)
				(type default)
			)
			(layer "F.Fab")
		)
		(fp_line
			(start 0.67945 0.3048)
			(end 0.120396 0.3048)
			(stroke
				(width 0.1)
				(type default)
			)
			(layer "F.Fab")
		)
		(fp_line
			(start 0.120396 0.3048)
			(end 0.120396 0.2794)
			(stroke
				(width 0.1)
				(type default)
			)
			(layer "F.Fab")
		)
		(fp_line
			(start -0.12065 0.3048)
			(end -0.67945 0.3048)
			(stroke
				(width 0.1)
				(type default)
			)
			(layer "F.Fab")
		)
		(fp_line
			(start -0.67945 0.3048)
			(end -0.67945 -0.305054)
			(stroke
				(width 0.1)
				(type default)
			)
			(layer "F.Fab")
		)
		(pad "1" smd circle
			(at -0.40005 0 90)
			(size 0 0)
			(layers "F.Cu" "F.Mask" "F.Paste")
			(net "P3V3_NIC4_PG_G1")
		)
		(pad "2" smd circle
			(at 0.40005 0 90)
			(size 0 0)
			(layers "F.Cu" "F.Mask" "F.Paste")
			(net "GND")
		)
	)
	(footprint ""
		(layer "F.Cu")
		(at 138.127994 -35.876738)
		(property "Reference" "R6059"
			(at 0 0 0)
			(layer "F.SilkS")
			(hide yes)
			(effects
				(font
					(size 1.27 1.27)
				)
			)
		)
		(property "Value" ""
			(at 0 0 0)
			(layer "F.Fab")
			(effects
				(font
					(size 1.27 1.27)
				)
			)
		)
		(duplicate_pad_numbers_are_jumpers no)
		(fp_line
			(start -0.7874 -0.4064)
			(end 0.7874 -0.4064)
			(stroke
				(width 0.1524)
				(type default)
			)
			(layer "F.SilkS")
		)
		(fp_line
			(start -0.7874 0.4064)
			(end -0.7874 -0.4064)
			(stroke
				(width 0.1524)
				(type default)
			)
			(layer "F.SilkS")
		)
		(fp_line
			(start 0.7874 -0.4064)
			(end 0.7874 0.4064)
			(stroke
				(width 0.1524)
				(type default)
			)
			(layer "F.SilkS")
		)
		(fp_line
			(start 0.7874 0.4064)
			(end -0.7874 0.4064)
			(stroke
				(width 0.1524)
				(type default)
			)
			(layer "F.SilkS")
		)
		(fp_line
			(start -0.67945 -0.305054)
			(end -0.12065 -0.305054)
			(stroke
				(width 0.1)
				(type default)
			)
			(layer "F.Fab")
		)
		(fp_line
			(start -0.67945 0.3048)
			(end -0.67945 -0.305054)
			(stroke
				(width 0.1)
				(type default)
			)
			(layer "F.Fab")
		)
		(fp_line
			(start -0.12065 -0.305054)
			(end -0.12065 -0.2794)
			(stroke
				(width 0.1)
				(type default)
			)
			(layer "F.Fab")
		)
		(fp_line
			(start -0.12065 -0.2794)
			(end 0.12065 -0.2794)
			(stroke
				(width 0.1)
				(type default)
			)
			(layer "F.Fab")
		)
		(fp_line
			(start -0.12065 0.2794)
			(end -0.12065 0.3048)
			(stroke
				(width 0.1)
				(type default)
			)
			(layer "F.Fab")
		)
		(fp_line
			(start -0.12065 0.3048)
			(end -0.67945 0.3048)
			(stroke
				(width 0.1)
				(type default)
			)
			(layer "F.Fab")
		)
		(fp_line
			(start 0.120396 0.2794)
			(end -0.12065 0.2794)
			(stroke
				(width 0.1)
				(type default)
			)
			(layer "F.Fab")
		)
		(fp_line
			(start 0.120396 0.3048)
			(end 0.120396 0.2794)
			(stroke
				(width 0.1)
				(type default)
			)
			(layer "F.Fab")
		)
		(fp_line
			(start 0.12065 -0.3048)
			(end 0.67945 -0.3048)
			(stroke
				(width 0.1)
				(type default)
			)
			(layer "F.Fab")
		)
		(fp_line
			(start 0.12065 -0.2794)
			(end 0.12065 -0.3048)
			(stroke
				(width 0.1)
				(type default)
			)
			(layer "F.Fab")
		)
		(fp_line
			(start 0.67945 -0.3048)
			(end 0.67945 0.3048)
			(stroke
				(width 0.1)
				(type default)
			)
			(layer "F.Fab")
		)
		(fp_line
			(start 0.67945 0.3048)
			(end 0.120396 0.3048)
			(stroke
				(width 0.1)
				(type default)
			)
			(layer "F.Fab")
		)
		(pad "1" smd circle
			(at -0.40005 0)
			(size 0 0)
			(layers "F.Cu" "F.Mask" "F.Paste")
			(net "PWRGD_P3V3_SSD5_D")
		)
		(pad "2" smd circle
			(at 0.40005 0)
			(size 0 0)
			(layers "F.Cu" "F.Mask" "F.Paste")
			(net "PWRGD_P3V3_SSD5_R")
		)
	)
)
